FILE_TYPE = CONNECTIVITY;
{Allegro Design Entry HDL 17.2-2016 S081 (4005846) 1/11/2022}
"PAGE_NUMBER" = 103;
0"NC";
1"M_G_CPU1_SA_CB<7:0>";
2"M_G_CPU1_SB_CA<6:0>";
3"M_G_CPU1_SB_CB<7:0>";
4"M_G_CPU1_SA_DQ<31:0>";
5"M_G_CPU1_SB_DQ<31:0>";
6"M_G_CPU1_SA_DQS_DP<9:0>";
7"M_G_CPU1_SB_DQS_DN<9:0>";
8"M_G_CPU1_SB_DQS_DP<9:0>";
9"M_G_CPU1_SA_CA<6:0>";
10"GND\g";
11"GND\g";
12"P3V3_STBY\g";
13"P3V3_STBY\g";
14"M_G_CPU1_SA_DQS_DN<9:0>";
15"I3C_SPD_DDRGL_CPU1_SCL";
16"I3C_SPD_DDRG_CPU1_SCL";
17"PWRGD_CHG_CPU1_DIMM0";
18"TP_CHG_CPU1_DIMM0_RFU_6";
19"P3V3_STBY\g";
20"TP_CHG_CPU1_DIMM0_RFU_5";
21"I3C_SPD_DDRGL_CPU1_SDA";
22"PD_CHG_CPU1_DIMM0_SAA";
23"M_G_CPU1_ALERT_N";
24"TP_CHG_CPU1_DIMM0_RFU_4";
25"M_G_CPU1_RESET_N";
26"TP_CHG_CPU1_DIMM0_RFU_2";
27"M_G_CPU1_SA_CA<3>";
28"M_G_CPU1_SA_CA<2>";
29"M_G_CPU1_SA_CA<1>";
30"M_G_CPU1_SA_CA<0>";
31"P12V_MEM_1\g";
32"GND\g";
33"GND\g";
34"M_G_CPU1_SB_DQS_DP<9>";
35"M_G_CPU1_SB_DQS_DN<9>";
36"M_G_CPU1_SA_DQS_DP<9>";
37"M_G_CPU1_SA_DQS_DN<9>";
38"M_G_CPU1_SA_DQS_DP<8>";
39"M_G_CPU1_SA_DQS_DN<8>";
40"M_G_CPU1_SB_DQS_DN<7>";
41"M_G_CPU1_SA_DQS_DP<7>";
42"M_G_CPU1_SB_DQS_DP<6>";
43"M_G_CPU1_SB_DQS_DN<6>";
44"M_G_CPU1_SA_DQS_DN<6>";
45"M_G_CPU1_SB_DQS_DP<5>";
46"M_G_CPU1_SB_DQS_DN<5>";
47"M_G_CPU1_SA_DQS_DP<5>";
48"M_G_CPU1_SA_DQS_DN<5>";
49"M_G_CPU1_SB_DQS_DP<4>";
50"M_G_CPU1_SB_DQS_DN<4>";
51"M_G_CPU1_SA_DQS_DP<4>";
52"M_G_CPU1_SA_DQS_DN<4>";
53"M_G_CPU1_SB_DQS_DP<3>";
54"M_G_CPU1_SB_DQS_DN<3>";
55"M_G_CPU1_SA_DQS_DP<3>";
56"M_G_CPU1_SA_DQS_DN<3>";
57"M_G_CPU1_SB_DQS_DP<2>";
58"M_G_CPU1_SB_DQS_DN<2>";
59"M_G_CPU1_SA_DQS_DP<2>";
60"M_G_CPU1_SA_DQS_DN<2>";
61"M_G_CPU1_SB_DQS_DP<1>";
62"M_G_CPU1_SB_DQS_DN<1>";
63"M_G_CPU1_SA_DQS_DP<1>";
64"M_G_CPU1_SA_DQS_DN<1>";
65"M_G_CPU1_SB_DQS_DP<0>";
66"M_G_CPU1_SB_DQS_DN<0>";
67"M_G_CPU1_SA_DQS_DP<0>";
68"M_G_CPU1_SA_DQS_DN<0>";
69"M_G_CPU1_SB_DQS_DP<7>";
70"M_G_CPU1_SB_DQS_DN<8>";
71"M_G_CPU1_SB_DQS_DP<8>";
72"M_G_CPU1_SA_DQS_DP<6>";
73"M_G_CPU1_SA_DQS_DN<7>";
74"TP_CHG_CPU1_DIMM0_RFU_0";
75"TP_CHG_CPU1_DIMM0_RFU_1";
76"TP_CHG_CPU1_DIMM0_RFU_3";
77"M_G_CPU1_SB_PAR";
78"M_G_CPU1_SA_PAR";
79"M_G_CPU1_SB_RSP<0>";
80"M_G_CPU1_SA_RSP<0>";
81"M_G_CPU1_SB_DQ<0>";
82"M_G_CPU1_SB_DQ<1>";
83"M_G_CPU1_SB_DQ<2>";
84"M_G_CPU1_SB_DQ<3>";
85"M_G_CPU1_SB_DQ<4>";
86"M_G_CPU1_SB_DQ<5>";
87"M_G_CPU1_SB_DQ<6>";
88"M_G_CPU1_SB_DQ<7>";
89"M_G_CPU1_SB_DQ<8>";
90"M_G_CPU1_SB_DQ<9>";
91"M_G_CPU1_SB_DQ<10>";
92"M_G_CPU1_SB_DQ<11>";
93"M_G_CPU1_SB_DQ<12>";
94"M_G_CPU1_SB_DQ<13>";
95"M_G_CPU1_SB_DQ<14>";
96"M_G_CPU1_SB_DQ<15>";
97"M_G_CPU1_SB_DQ<16>";
98"M_G_CPU1_SB_DQ<17>";
99"M_G_CPU1_SB_DQ<18>";
100"M_G_CPU1_SB_DQ<19>";
101"M_G_CPU1_SB_DQ<20>";
102"M_G_CPU1_SB_DQ<21>";
103"M_G_CPU1_SB_DQ<22>";
104"M_G_CPU1_SB_DQ<23>";
105"M_G_CPU1_SB_DQ<24>";
106"M_G_CPU1_SB_DQ<25>";
107"M_G_CPU1_SB_DQ<26>";
108"M_G_CPU1_SB_DQ<27>";
109"M_G_CPU1_SB_DQ<28>";
110"M_G_CPU1_SB_DQ<29>";
111"M_G_CPU1_SB_DQ<30>";
112"M_G_CPU1_SB_DQ<31>";
113"M_G_CPU1_SA_DQ<0>";
114"M_G_CPU1_SA_DQ<1>";
115"M_G_CPU1_SA_DQ<2>";
116"M_G_CPU1_SA_DQ<3>";
117"M_G_CPU1_SA_DQ<4>";
118"M_G_CPU1_SA_DQ<5>";
119"M_G_CPU1_SA_DQ<6>";
120"M_G_CPU1_SA_DQ<7>";
121"M_G_CPU1_SA_DQ<8>";
122"M_G_CPU1_SA_DQ<9>";
123"M_G_CPU1_SA_DQ<10>";
124"M_G_CPU1_SA_DQ<11>";
125"M_G_CPU1_SA_DQ<12>";
126"M_G_CPU1_SA_DQ<13>";
127"M_G_CPU1_SA_DQ<14>";
128"M_G_CPU1_SA_DQ<15>";
129"M_G_CPU1_SA_DQ<16>";
130"M_G_CPU1_SA_DQ<17>";
131"M_G_CPU1_SA_DQ<18>";
132"M_G_CPU1_SA_DQ<19>";
133"M_G_CPU1_SA_DQ<20>";
134"M_G_CPU1_SA_DQ<21>";
135"M_G_CPU1_SA_DQ<22>";
136"M_G_CPU1_SA_DQ<23>";
137"M_G_CPU1_SA_DQ<24>";
138"M_G_CPU1_SA_DQ<25>";
139"M_G_CPU1_SA_DQ<26>";
140"M_G_CPU1_SA_DQ<27>";
141"M_G_CPU1_SA_DQ<28>";
142"M_G_CPU1_SA_DQ<29>";
143"M_G_CPU1_SA_DQ<30>";
144"M_G_CPU1_SB_CS_N<1>";
145"M_G_CPU1_SA_CS_N<1>";
146"M_G_CPU1_SB_CS_N<0>";
147"M_G_CPU1_SA_CS_N<0>";
148"M_G_CPU1_CLK_DP<0>";
149"M_G_CPU1_CLK_DN<0>";
150"M_G_CPU1_SB_CB<0>";
151"M_G_CPU1_SB_CB<1>";
152"M_G_CPU1_SB_CB<2>";
153"M_G_CPU1_SB_CB<3>";
154"M_G_CPU1_SB_CB<4>";
155"M_G_CPU1_SB_CB<5>";
156"M_G_CPU1_SB_CB<6>";
157"M_G_CPU1_SA_CB<0>";
158"M_G_CPU1_SA_CB<2>";
159"M_G_CPU1_SA_CB<3>";
160"M_G_CPU1_SA_CB<5>";
161"M_G_CPU1_SA_CB<6>";
162"M_G_CPU1_SB_CA<6>";
163"M_G_CPU1_SA_CA<6>";
164"M_G_CPU1_SB_CA<5>";
165"M_G_CPU1_SA_CA<5>";
166"M_G_CPU1_SB_CA<4>";
167"M_G_CPU1_SA_CA<4>";
168"M_G_CPU1_SB_CA<3>";
169"M_G_CPU1_SB_CA<2>";
170"M_G_CPU1_SB_CA<1>";
171"M_G_CPU1_SB_CA<0>";
172"M_G_CPU1_SB_CB<7>";
173"M_G_CPU1_SA_CB<1>";
174"M_G_CPU1_SA_CB<4>";
175"M_G_CPU1_SA_CB<7>";
176"M_G_CPU1_SA_DQ<31>";
177"GND\g";
178"PWRGD_CHGL_CPU1";
179"PD_CHG_CPU1_DIMM0_SAA";
%"TAP"
"1","(-5775,4100)","0","mstr_standard","I100";
;
CDS_LIB"mstr_standard"
BODY_TYPE"PLUMBING"
HDL_TAP"TRUE";
"B \NAC \NWC"4;
"S \NAC"
BN"6"119;
%"TAP"
"1","(-5775,4250)","0","mstr_standard","I101";
;
CDS_LIB"mstr_standard"
BODY_TYPE"PLUMBING"
HDL_TAP"TRUE";
"B \NAC \NWC"4;
"S \NAC"
BN"9"122;
%"TAP"
"1","(-5775,4200)","0","mstr_standard","I102";
;
CDS_LIB"mstr_standard"
BODY_TYPE"PLUMBING"
HDL_TAP"TRUE";
"B \NAC \NWC"4;
"S \NAC"
BN"8"121;
%"TAP"
"1","(-5775,4050)","0","mstr_standard","I103";
;
CDS_LIB"mstr_standard"
BODY_TYPE"PLUMBING"
HDL_TAP"TRUE";
"B \NAC \NWC"4;
"S \NAC"
BN"5"118;
%"TAP"
"1","(-5775,4450)","0","mstr_standard","I104";
;
CDS_LIB"mstr_standard"
BODY_TYPE"PLUMBING"
HDL_TAP"TRUE";
"B \NAC \NWC"4;
"S \NAC"
BN"13"126;
%"TAP"
"1","(-5775,4500)","0","mstr_standard","I105";
;
CDS_LIB"mstr_standard"
BODY_TYPE"PLUMBING"
HDL_TAP"TRUE";
"B \NAC \NWC"4;
"S \NAC"
BN"14"127;
%"TAP"
"1","(-5775,4300)","0","mstr_standard","I106";
;
CDS_LIB"mstr_standard"
BODY_TYPE"PLUMBING"
HDL_TAP"TRUE";
"B \NAC \NWC"4;
"S \NAC"
BN"10"123;
%"TAP"
"1","(-5775,4350)","0","mstr_standard","I107";
;
CDS_LIB"mstr_standard"
BODY_TYPE"PLUMBING"
HDL_TAP"TRUE";
"B \NAC \NWC"4;
"S \NAC"
BN"11"124;
%"TAP"
"1","(-5775,4400)","0","mstr_standard","I108";
;
CDS_LIB"mstr_standard"
BODY_TYPE"PLUMBING"
HDL_TAP"TRUE";
"B \NAC \NWC"4;
"S \NAC"
BN"12"125;
%"TAP"
"1","(-5775,4700)","0","mstr_standard","I109";
;
CDS_LIB"mstr_standard"
BODY_TYPE"PLUMBING"
HDL_TAP"TRUE";
"B \NAC \NWC"4;
"S \NAC"
BN"18"131;
%"TAP"
"1","(-5775,4750)","0","mstr_standard","I110";
;
CDS_LIB"mstr_standard"
BODY_TYPE"PLUMBING"
HDL_TAP"TRUE";
"B \NAC \NWC"4;
"S \NAC"
BN"19"132;
%"TAP"
"1","(-5775,4550)","0","mstr_standard","I111";
;
CDS_LIB"mstr_standard"
BODY_TYPE"PLUMBING"
HDL_TAP"TRUE";
"B \NAC \NWC"4;
"S \NAC"
BN"15"128;
%"TAP"
"1","(-5775,4600)","0","mstr_standard","I112";
;
CDS_LIB"mstr_standard"
BODY_TYPE"PLUMBING"
HDL_TAP"TRUE";
"B \NAC \NWC"4;
"S \NAC"
BN"16"129;
%"TAP"
"1","(-5775,4650)","0","mstr_standard","I113";
;
CDS_LIB"mstr_standard"
BODY_TYPE"PLUMBING"
HDL_TAP"TRUE";
"B \NAC \NWC"4;
"S \NAC"
BN"17"130;
%"TAP"
"1","(-5775,5000)","0","mstr_standard","I114";
;
CDS_LIB"mstr_standard"
BODY_TYPE"PLUMBING"
HDL_TAP"TRUE";
"B \NAC \NWC"4;
"S \NAC"
BN"24"137;
%"TAP"
"1","(-5775,4950)","0","mstr_standard","I115";
;
CDS_LIB"mstr_standard"
BODY_TYPE"PLUMBING"
HDL_TAP"TRUE";
"B \NAC \NWC"4;
"S \NAC"
BN"23"136;
%"TAP"
"1","(-5775,5050)","0","mstr_standard","I116";
;
CDS_LIB"mstr_standard"
BODY_TYPE"PLUMBING"
HDL_TAP"TRUE";
"B \NAC \NWC"4;
"S \NAC"
BN"25"138;
%"TAP"
"1","(-5775,4800)","0","mstr_standard","I117";
;
CDS_LIB"mstr_standard"
BODY_TYPE"PLUMBING"
HDL_TAP"TRUE";
"B \NAC \NWC"4;
"S \NAC"
BN"20"133;
%"TAP"
"1","(-5775,4850)","0","mstr_standard","I118";
;
CDS_LIB"mstr_standard"
BODY_TYPE"PLUMBING"
HDL_TAP"TRUE";
"B \NAC \NWC"4;
"S \NAC"
BN"21"134;
%"TAP"
"1","(-5775,4900)","0","mstr_standard","I119";
;
CDS_LIB"mstr_standard"
BODY_TYPE"PLUMBING"
HDL_TAP"TRUE";
"B \NAC \NWC"4;
"S \NAC"
BN"22"135;
%"TAP"
"1","(-5775,5300)","0","mstr_standard","I120";
;
CDS_LIB"mstr_standard"
BODY_TYPE"PLUMBING"
HDL_TAP"TRUE";
"B \NAC \NWC"4;
"S \NAC"
BN"30"143;
%"TAP"
"1","(-5775,5200)","0","mstr_standard","I121";
;
CDS_LIB"mstr_standard"
BODY_TYPE"PLUMBING"
HDL_TAP"TRUE";
"B \NAC \NWC"4;
"S \NAC"
BN"28"141;
%"TAP"
"1","(-5775,5250)","0","mstr_standard","I122";
;
CDS_LIB"mstr_standard"
BODY_TYPE"PLUMBING"
HDL_TAP"TRUE";
"B \NAC \NWC"4;
"S \NAC"
BN"29"142;
%"TAP"
"1","(-5775,5150)","0","mstr_standard","I123";
;
CDS_LIB"mstr_standard"
BODY_TYPE"PLUMBING"
HDL_TAP"TRUE";
"B \NAC \NWC"4;
"S \NAC"
BN"27"140;
%"TAP"
"1","(-5775,5100)","0","mstr_standard","I124";
;
CDS_LIB"mstr_standard"
BODY_TYPE"PLUMBING"
HDL_TAP"TRUE";
"B \NAC \NWC"4;
"S \NAC"
BN"26"139;
%"TAP"
"1","(-5775,5350)","0","mstr_standard","I125";
;
CDS_LIB"mstr_standard"
BODY_TYPE"PLUMBING"
HDL_TAP"TRUE";
"B \NAC \NWC"4;
"S \NAC"
BN"31"176;
%"GND"
"1","(-6200,900)","0","mstr_symbols","I128";
;
SIZE"1B"
BOM_COST"MEM"
CDS_LIB"mstr_symbols"
BODY_TYPE"PLUMBING"
VOLTAGE"0.0"
HDL_POWER"GND";
"A\NAC"10;
%"Q_RES"
"2","(-6200,1125)","0","pure_quanta","I129";
;
LOCATION"R37"
SEC"1"
WATTAGE"1/16W"
MATERIAL"CHIP"
TOLERANCE"1%"
VALUE"10K"
PART_NUMBER"CS31002FB08"
PACK_TYPE"0402LF"
BOM_COST"MEM"
CDS_LIB"pure_quanta"
SEC_TYPE"0402LF"
ROOM"MEM_CH_A_CPU1_DIMM1";
"A"
$PN"1"
XNET_PINS"3"179;
"B"
$PN"2"
XNET_PINS"2"10;
%"GND"
"1","(-2125,1875)","0","mstr_symbols","I140";
;
CDS_LIB"mstr_symbols"
SIZE"1B"
BODY_TYPE"PLUMBING"
VOLTAGE"0.0"
HDL_POWER"GND";
"A\NAC"33;
%"GND"
"1","(-525,1675)","0","mstr_symbols","I141";
;
CDS_LIB"mstr_symbols"
SIZE"1B"
BODY_TYPE"PLUMBING"
VOLTAGE"0.0"
HDL_POWER"GND";
"A\NAC"32;
%"SCONN288_DDR506112002KQ"
"3","(-1325,3625)","0","pure_quanta","I142";
;
LOCATION"J102"
$SEC"3"
CDS_SEC"3"
PART_TYPE"SMLF"
MATERIAL"IO"
VALUE"SCONN288_DDR506112002KQ"
PART_NUMBER"DFHST8FS479"
CDS_LMAN_SYM_OUTLINE"-450,1800,450,-1750"
NEEDS_NO_SIZE"TRUE"
CDS_LIB"pure_quanta";
"G3"
$PN"G3"32;
"G2"
$PN"G2"32;
"G1"
$PN"G1"32;
"VSS62"
$PN"141"32;
"VSS61"
$PN"139"32;
"VSS60"
$PN"136"32;
"VSS58"
$PN"132"32;
"VSS104"
$PN"240"33;
"VSS102"
$PN"235"33;
"VSS100"
$PN"230"33;
"VIN_BULK2"
$PN"146"31;
"VIN_BULK1"
$PN"145"31;
"VIN_BULK0"
$PN"1"31;
"VSS126"
$PN"288"33;
"VSS125"
$PN"286"33;
"VSS124"
$PN"284"33;
"VSS123"
$PN"281"33;
"VSS122"
$PN"279"33;
"VSS121"
$PN"277"33;
"VSS120"
$PN"275"33;
"VSS119"
$PN"273"33;
"VSS118"
$PN"270"33;
"VSS117"
$PN"268"33;
"VSS116"
$PN"266"33;
"VSS115"
$PN"264"33;
"VSS114"
$PN"262"33;
"VSS113"
$PN"259"33;
"VSS112"
$PN"257"33;
"VSS111"
$PN"255"33;
"VSS110"
$PN"253"33;
"VSS109"
$PN"251"33;
"VSS108"
$PN"248"33;
"VSS107"
$PN"246"33;
"VSS106"
$PN"244"33;
"VSS105"
$PN"242"33;
"VSS103"
$PN"237"33;
"VSS101"
$PN"233"33;
"VSS99"
$PN"228"33;
"VSS98"
$PN"226"33;
"VSS97"
$PN"224"33;
"VSS96"
$PN"222"33;
"VSS95"
$PN"219"33;
"VSS94"
$PN"216"33;
"VSS93"
$PN"214"33;
"VSS92"
$PN"212"33;
"VSS91"
$PN"210"33;
"VSS90"
$PN"208"33;
"VSS89"
$PN"206"33;
"VSS88"
$PN"204"33;
"VSS87"
$PN"202"33;
"VSS86"
$PN"199"33;
"VSS85"
$PN"197"33;
"VSS84"
$PN"195"33;
"VSS83"
$PN"193"33;
"VSS82"
$PN"191"33;
"VSS81"
$PN"188"33;
"VSS80"
$PN"186"33;
"VSS79"
$PN"184"33;
"VSS78"
$PN"182"33;
"VSS77"
$PN"180"33;
"VSS76"
$PN"177"33;
"VSS75"
$PN"175"33;
"VSS74"
$PN"173"33;
"VSS73"
$PN"171"33;
"VSS72"
$PN"169"33;
"VSS71"
$PN"166"33;
"VSS70"
$PN"164"33;
"VSS69"
$PN"162"33;
"VSS68"
$PN"160"33;
"VSS67"
$PN"158"33;
"VSS66"
$PN"155"33;
"VSS65"
$PN"153"33;
"VSS64"
$PN"151"33;
"VSS63"
$PN"143"32;
"VSS59"
$PN"134"32;
"VSS57"
$PN"130"32;
"VSS56"
$PN"128"32;
"VSS55"
$PN"125"32;
"VSS54"
$PN"123"32;
"VSS53"
$PN"121"32;
"VSS52"
$PN"119"32;
"VSS51"
$PN"117"32;
"VSS50"
$PN"114"32;
"VSS49"
$PN"112"32;
"VSS48"
$PN"110"32;
"VSS47"
$PN"108"32;
"VSS46"
$PN"106"32;
"VSS45"
$PN"103"32;
"VSS44"
$PN"101"32;
"VSS43"
$PN"99"32;
"VSS42"
$PN"97"32;
"VSS41"
$PN"95"32;
"VSS40"
$PN"92"32;
"VSS39"
$PN"90"32;
"VSS38"
$PN"88"32;
"VSS37"
$PN"85"32;
"VSS36"
$PN"83"32;
"VSS35"
$PN"81"32;
"VSS34"
$PN"79"32;
"VSS33"
$PN"77"32;
"VSS32"
$PN"75"32;
"VSS31"
$PN"73"32;
"VSS30"
$PN"71"32;
"VSS29"
$PN"69"32;
"VSS28"
$PN"67"32;
"VSS27"
$PN"65"32;
"VSS26"
$PN"63"32;
"VSS25"
$PN"61"32;
"VSS24"
$PN"59"32;
"VSS23"
$PN"57"32;
"VSS22"
$PN"54"32;
"VSS21"
$PN"52"32;
"VSS20"
$PN"50"32;
"VSS19"
$PN"48"32;
"VSS18"
$PN"46"32;
"VSS17"
$PN"43"32;
"VSS16"
$PN"41"32;
"VSS15"
$PN"39"32;
"VSS14"
$PN"37"32;
"VSS13"
$PN"35"32;
"VSS12"
$PN"32"32;
"VSS11"
$PN"30"32;
"VSS10"
$PN"28"32;
"VSS9"
$PN"26"32;
"VSS8"
$PN"24"32;
"VSS7"
$PN"21"32;
"VSS6"
$PN"19"32;
"VSS5"
$PN"17"32;
"VSS4"
$PN"15"32;
"VSS3"
$PN"13"32;
"VSS2"
$PN"10"32;
"VSS1"
$PN"8"32;
"VSS0"
$PN"6"32;
%"Q_CAP"
"1","(-8675,3200)","2","pure_quanta","I185";
;
LOCATION"C160"
$SEC"1"
CDS_SEC"1"
MATERIAL"X7R"
TOLERANCE"10%"
VALUE"0.1UF"
VOLTAGE"25V"
PACK_TYPE"0402"
PART_NUMBER"CH4104K1B00"
BOM_COST"MEM"
CDS_LIB"pure_quanta"
ROOM"MEM_CH_A_CPU0_DIMM1";
"B"
$PN"2"11;
"A"
$PN"1"19;
%"GND"
"1","(-8675,2975)","0","mstr_symbols","I186";
;
BOM_COST"MEM"
SIZE"1B"
CDS_LIB"mstr_symbols"
BODY_TYPE"PLUMBING"
VOLTAGE"0"
ROOM"MEM_EFGH_DECOUPLING_CAPS"
HDL_POWER"GND";
"A\NAC"11;
%"Q_RES"
"1","(-8400,2100)","2","pure_quanta","I188";
;
LOCATION"R1184"
$SEC"1"
CDS_SEC"1"
VALUE"0"
CDS_LIB"pure_quanta"
BOM_COST"MEM"
WATTAGE"1/16W"
MATERIAL"CHIP"
TOLERANCE"5%"
PART_NUMBER"CS00002JB38"
PACK_TYPE"0402LF"
ROOM"RST_CPU0_PLD_TO_DIMM";
"B"
$PN"2"178;
"A"
$PN"1"17;
%"Q_RES"
"2","(-8525,2250)","2","pure_quanta","I189";
;
LOCATION"R109"
$SEC"1"
CDS_SEC"1"
MATERIAL"CHIP"
TOLERANCE"5%"
VALUE"1K"
PART_NUMBER"TMP_QCS21002JB34"
PACK_TYPE"0402LF"
WATTAGE"1/16W"
BOM_COST"MEM"
CDS_LIB"pure_quanta"
ROOM"MEM_CH_A_CPU0_DIMM1";
"A"
$PN"1"12;
"B"
$PN"2"178;
%"VCC_CORE"
"1","(-8525,2425)","0","mstr_symbols","I190";
;
HDL_POWER"P3V3_STBY"
CDS_LIB"mstr_symbols"
VOLTAGE"3.3"
ROOM"PVCCINFAON_CPU0_CTRL";
"A"12;
%"VCC_CORE"
"1","(-8275,2425)","0","mstr_symbols","I191";
;
HDL_POWER"P3V3_STBY"
CDS_LIB"mstr_symbols"
VOLTAGE"3.3"
ROOM"PVCCINFAON_CPU0_CTRL";
"A"13;
%"Q_RES"
"2","(-8275,2250)","0","pure_quanta","I192";
;
LOCATION"R110"
$SEC"1"
CDS_SEC"1"
WATTAGE"1/16W"
MATERIAL"EMPTY"
TOLERANCE"5%"
VALUE"1K"
PACK_TYPE"0402LF"
CDS_LIB"pure_quanta"
BOM_COST"MEM"
PART_NUMBER"TMP_QCS21002JB34"
ROOM"MEM_CH_A_CPU0_DIMM1";
"A"
$PN"1"13;
"B"
$PN"2"17;
%"TAP"
"1","(-3050,4375)","0","mstr_standard","I198";
;
CDS_LIB"mstr_standard"
BODY_TYPE"PLUMBING"
HDL_TAP"TRUE";
"B \NAC \NWC"14;
"S \NAC"
BN"9"37;
%"TAP"
"1","(-3050,4275)","0","mstr_standard","I199";
;
CDS_LIB"mstr_standard"
BODY_TYPE"PLUMBING"
HDL_TAP"TRUE";
"B \NAC \NWC"14;
"S \NAC"
BN"8"39;
%"TAP"
"1","(-3250,4425)","0","mstr_standard","I200";
;
CDS_LIB"mstr_standard"
BODY_TYPE"PLUMBING"
HDL_TAP"TRUE";
"B \NAC \NWC"6;
"S \NAC"
BN"9"36;
%"TAP"
"1","(-3250,4325)","0","mstr_standard","I201";
;
CDS_LIB"mstr_standard"
BODY_TYPE"PLUMBING"
HDL_TAP"TRUE";
"B \NAC \NWC"6;
"S \NAC"
BN"8"38;
%"TAP"
"1","(-3050,4175)","0","mstr_standard","I202";
;
CDS_LIB"mstr_standard"
BODY_TYPE"PLUMBING"
HDL_TAP"TRUE";
"B \NAC \NWC"14;
"S \NAC"
BN"7"73;
%"TAP"
"1","(-3050,4075)","0","mstr_standard","I203";
;
CDS_LIB"mstr_standard"
BODY_TYPE"PLUMBING"
HDL_TAP"TRUE";
"B \NAC \NWC"14;
"S \NAC"
BN"6"44;
%"TAP"
"1","(-3050,3875)","0","mstr_standard","I204";
;
CDS_LIB"mstr_standard"
BODY_TYPE"PLUMBING"
HDL_TAP"TRUE";
"B \NAC \NWC"14;
"S \NAC"
BN"4"52;
%"TAP"
"1","(-3050,3975)","0","mstr_standard","I205";
;
CDS_LIB"mstr_standard"
BODY_TYPE"PLUMBING"
HDL_TAP"TRUE";
"B \NAC \NWC"14;
"S \NAC"
BN"5"48;
%"TAP"
"1","(-3050,3775)","0","mstr_standard","I206";
;
CDS_LIB"mstr_standard"
BODY_TYPE"PLUMBING"
HDL_TAP"TRUE";
"B \NAC \NWC"14;
"S \NAC"
BN"3"56;
%"TAP"
"1","(-3250,4225)","0","mstr_standard","I207";
;
CDS_LIB"mstr_standard"
BODY_TYPE"PLUMBING"
HDL_TAP"TRUE";
"B \NAC \NWC"6;
"S \NAC"
BN"7"41;
%"TAP"
"1","(-3250,4125)","0","mstr_standard","I208";
;
CDS_LIB"mstr_standard"
BODY_TYPE"PLUMBING"
HDL_TAP"TRUE";
"B \NAC \NWC"6;
"S \NAC"
BN"6"72;
%"TAP"
"1","(-3250,4025)","0","mstr_standard","I209";
;
CDS_LIB"mstr_standard"
BODY_TYPE"PLUMBING"
HDL_TAP"TRUE";
"B \NAC \NWC"6;
"S \NAC"
BN"5"47;
%"TAP"
"1","(-3250,3925)","0","mstr_standard","I210";
;
CDS_LIB"mstr_standard"
BODY_TYPE"PLUMBING"
HDL_TAP"TRUE";
"B \NAC \NWC"6;
"S \NAC"
BN"4"51;
%"TAP"
"1","(-3250,3825)","0","mstr_standard","I211";
;
CDS_LIB"mstr_standard"
BODY_TYPE"PLUMBING"
HDL_TAP"TRUE";
"B \NAC \NWC"6;
"S \NAC"
BN"3"55;
%"TAP"
"1","(-3050,3675)","0","mstr_standard","I212";
;
CDS_LIB"mstr_standard"
BODY_TYPE"PLUMBING"
HDL_TAP"TRUE";
"B \NAC \NWC"14;
"S \NAC"
BN"2"60;
%"TAP"
"1","(-3050,3575)","0","mstr_standard","I213";
;
CDS_LIB"mstr_standard"
BODY_TYPE"PLUMBING"
HDL_TAP"TRUE";
"B \NAC \NWC"14;
"S \NAC"
BN"1"64;
%"TAP"
"1","(-3050,3475)","0","mstr_standard","I214";
;
CDS_LIB"mstr_standard"
BODY_TYPE"PLUMBING"
HDL_TAP"TRUE";
"B \NAC \NWC"14;
"S \NAC"
BN"0"68;
%"TAP"
"1","(-3050,3325)","0","mstr_standard","I215";
;
CDS_LIB"mstr_standard"
BODY_TYPE"PLUMBING"
HDL_TAP"TRUE";
"B \NAC \NWC"7;
"S \NAC"
BN"9"35;
%"TAP"
"1","(-3050,3225)","0","mstr_standard","I216";
;
CDS_LIB"mstr_standard"
BODY_TYPE"PLUMBING"
HDL_TAP"TRUE";
"B \NAC \NWC"7;
"S \NAC"
BN"8"70;
%"TAP"
"1","(-3250,3725)","0","mstr_standard","I217";
;
CDS_LIB"mstr_standard"
BODY_TYPE"PLUMBING"
HDL_TAP"TRUE";
"B \NAC \NWC"6;
"S \NAC"
BN"2"59;
%"TAP"
"1","(-3250,3625)","0","mstr_standard","I218";
;
CDS_LIB"mstr_standard"
BODY_TYPE"PLUMBING"
HDL_TAP"TRUE";
"B \NAC \NWC"6;
"S \NAC"
BN"1"63;
%"TAP"
"1","(-3250,3525)","0","mstr_standard","I219";
;
CDS_LIB"mstr_standard"
BODY_TYPE"PLUMBING"
HDL_TAP"TRUE";
"B \NAC \NWC"6;
"S \NAC"
BN"0"67;
%"SCONN288_DDR506112002KQ"
"1","(-6625,3600)","0","pure_quanta","I22";
;
LOCATION"J102"
$SEC"1"
CDS_SEC"1"
VALUE"SCONN288_DDR506112002KQ"
PART_TYPE"SMLF"
MATERIAL"IO"
PART_NUMBER"DFHST8FS479"
CDS_LMAN_SYM_OUTLINE"-450,1900,450,-1850"
NEEDS_NO_SIZE"TRUE"
CDS_LIB"pure_quanta";
"PWR_GOOD||FAIL_N"
$PN"147"17;
"DQ31_A"
$PN"194"176;
"CB7_A"
$PN"205"175;
"CB4_A"
$PN"58"174;
"CB1_A"
$PN"53"173;
"CB7_B"
$PN"236"172;
"ALERT_N \B"
$PN"62"23;
"CA0_A"
$PN"66"30;
"CA0_B"
$PN"76"171;
"CA1_A"
$PN"211"29;
"CA1_B"
$PN"221"170;
"CA2_A"
$PN"68"28;
"CA2_B"
$PN"78"169;
"CA3_A"
$PN"213"27;
"CA3_B"
$PN"223"168;
"CA4_A"
$PN"70"167;
"CA4_B"
$PN"80"166;
"CA5_A"
$PN"215"165;
"CA5_B"
$PN"225"164;
"CA6_A"
$PN"72"163;
"CA6_B"
$PN"82"162;
"CB6_A"
$PN"203"161;
"CB5_A"
$PN"60"160;
"CB3_A"
$PN"198"159;
"CB2_A"
$PN"196"158;
"CB0_A"
$PN"51"157;
"CB6_B"
$PN"234"156;
"CB5_B"
$PN"91"155;
"CB4_B"
$PN"89"154;
"CB3_B"
$PN"243"153;
"CB2_B"
$PN"241"152;
"CB1_B"
$PN"98"151;
"CB0_B"
$PN"96"150;
"CK_C \B"
$PN"218"149;
"CK_T"
$PN"217"148;
"CS0_A_N"
$PN"64"147;
"CS0_B_N"
$PN"84"146;
"CS1_A_N"
$PN"209"145;
"CS1_B_N"
$PN"229"144;
"DQ30_A"
$PN"192"143;
"DQ29_A"
$PN"49"142;
"DQ28_A"
$PN"47"141;
"DQ27_A"
$PN"187"140;
"DQ26_A"
$PN"185"139;
"DQ25_A"
$PN"42"138;
"DQ24_A"
$PN"40"137;
"DQ23_A"
$PN"183"136;
"DQ22_A"
$PN"181"135;
"DQ21_A"
$PN"38"134;
"DQ20_A"
$PN"36"133;
"DQ19_A"
$PN"176"132;
"DQ18_A"
$PN"174"131;
"DQ17_A"
$PN"31"130;
"DQ16_A"
$PN"29"129;
"DQ15_A"
$PN"172"128;
"DQ14_A"
$PN"170"127;
"DQ13_A"
$PN"27"126;
"DQ12_A"
$PN"25"125;
"DQ11_A"
$PN"165"124;
"DQ10_A"
$PN"163"123;
"DQ9_A"
$PN"20"122;
"DQ8_A"
$PN"18"121;
"DQ7_A"
$PN"161"120;
"DQ6_A"
$PN"159"119;
"DQ5_A"
$PN"16"118;
"DQ4_A"
$PN"14"117;
"DQ3_A"
$PN"154"116;
"DQ2_A"
$PN"152"115;
"DQ1_A"
$PN"9"114;
"DQ0_A"
$PN"7"113;
"DQ31_B"
$PN"287"112;
"DQ30_B"
$PN"285"111;
"DQ29_B"
$PN"142"110;
"DQ28_B"
$PN"140"109;
"DQ27_B"
$PN"280"108;
"DQ26_B"
$PN"278"107;
"DQ25_B"
$PN"135"106;
"DQ24_B"
$PN"133"105;
"DQ23_B"
$PN"276"104;
"DQ22_B"
$PN"274"103;
"DQ21_B"
$PN"131"102;
"DQ20_B"
$PN"129"101;
"DQ19_B"
$PN"269"100;
"DQ18_B"
$PN"267"99;
"DQ17_B"
$PN"124"98;
"DQ16_B"
$PN"122"97;
"DQ15_B"
$PN"265"96;
"DQ14_B"
$PN"263"95;
"DQ13_B"
$PN"120"94;
"DQ12_B"
$PN"118"93;
"DQ11_B"
$PN"258"92;
"DQ10_B"
$PN"256"91;
"DQ9_B"
$PN"113"90;
"DQ8_B"
$PN"111"89;
"DQ7_B"
$PN"254"88;
"DQ6_B"
$PN"252"87;
"DQ5_B"
$PN"109"86;
"DQ4_B"
$PN"107"85;
"DQ3_B"
$PN"247"84;
"DQ2_B"
$PN"245"83;
"DQ1_B"
$PN"102"82;
"DQ0_B"
$PN"100"81;
"HAS"
$PN"148"22;
"HSCL"
$PN"4"16;
"HSDA"
$PN"5"21;
"LBD||RSP_A_N"
$PN"86"80;
"LBS||RSP_B_N"
$PN"87"79;
"PAR_A"
$PN"74"78;
"PAR_B"
$PN"227"77;
"RESET_N \B"
$PN"207"25;
"RFU6"
$PN"232"18;
"RFU5"
$PN"231"20;
"RFU4"
$PN"220"24;
"RFU3"
$PN"150"76;
"RFU2"
$PN"149"26;
"RFU1"
$PN"144"75;
"RFU0"
$PN"2"74;
"VIN_MGMT"
$PN"3"19;
%"TAP"
"1","(-3250,3375)","0","mstr_standard","I220";
;
CDS_LIB"mstr_standard"
BODY_TYPE"PLUMBING"
HDL_TAP"TRUE";
"B \NAC \NWC"8;
"S \NAC"
BN"9"34;
%"TAP"
"1","(-3250,3275)","0","mstr_standard","I221";
;
CDS_LIB"mstr_standard"
BODY_TYPE"PLUMBING"
HDL_TAP"TRUE";
"B \NAC \NWC"8;
"S \NAC"
BN"8"71;
%"TAP"
"1","(-3050,3125)","0","mstr_standard","I222";
;
CDS_LIB"mstr_standard"
BODY_TYPE"PLUMBING"
HDL_TAP"TRUE";
"B \NAC \NWC"7;
"S \NAC"
BN"7"40;
%"TAP"
"1","(-3050,3025)","0","mstr_standard","I223";
;
CDS_LIB"mstr_standard"
BODY_TYPE"PLUMBING"
HDL_TAP"TRUE";
"B \NAC \NWC"7;
"S \NAC"
BN"6"43;
%"TAP"
"1","(-3050,2925)","0","mstr_standard","I224";
;
CDS_LIB"mstr_standard"
BODY_TYPE"PLUMBING"
HDL_TAP"TRUE";
"B \NAC \NWC"7;
"S \NAC"
BN"5"46;
%"TAP"
"1","(-3050,2825)","0","mstr_standard","I225";
;
CDS_LIB"mstr_standard"
BODY_TYPE"PLUMBING"
HDL_TAP"TRUE";
"B \NAC \NWC"7;
"S \NAC"
BN"4"50;
%"TAP"
"1","(-3050,2725)","0","mstr_standard","I226";
;
CDS_LIB"mstr_standard"
BODY_TYPE"PLUMBING"
HDL_TAP"TRUE";
"B \NAC \NWC"7;
"S \NAC"
BN"3"54;
%"TAP"
"1","(-3250,3175)","0","mstr_standard","I227";
;
CDS_LIB"mstr_standard"
BODY_TYPE"PLUMBING"
HDL_TAP"TRUE";
"B \NAC \NWC"8;
"S \NAC"
BN"7"69;
%"TAP"
"1","(-3250,3075)","0","mstr_standard","I228";
;
CDS_LIB"mstr_standard"
BODY_TYPE"PLUMBING"
HDL_TAP"TRUE";
"B \NAC \NWC"8;
"S \NAC"
BN"6"42;
%"TAP"
"1","(-3250,2975)","0","mstr_standard","I229";
;
CDS_LIB"mstr_standard"
BODY_TYPE"PLUMBING"
HDL_TAP"TRUE";
"B \NAC \NWC"8;
"S \NAC"
BN"5"45;
%"TAP"
"1","(-7475,3200)","2","mstr_standard","I23";
;
CDS_LIB"mstr_standard"
BODY_TYPE"PLUMBING"
HDL_TAP"TRUE";
"B \NAC \NWC"3;
"S \NAC"
BN"1"151;
%"TAP"
"1","(-3250,2875)","0","mstr_standard","I230";
;
CDS_LIB"mstr_standard"
BODY_TYPE"PLUMBING"
HDL_TAP"TRUE";
"B \NAC \NWC"8;
"S \NAC"
BN"4"49;
%"TAP"
"1","(-3250,2775)","0","mstr_standard","I231";
;
CDS_LIB"mstr_standard"
BODY_TYPE"PLUMBING"
HDL_TAP"TRUE";
"B \NAC \NWC"8;
"S \NAC"
BN"3"53;
%"TAP"
"1","(-3050,2625)","0","mstr_standard","I232";
;
CDS_LIB"mstr_standard"
BODY_TYPE"PLUMBING"
HDL_TAP"TRUE";
"B \NAC \NWC"7;
"S \NAC"
BN"2"58;
%"TAP"
"1","(-3050,2525)","0","mstr_standard","I233";
;
CDS_LIB"mstr_standard"
BODY_TYPE"PLUMBING"
HDL_TAP"TRUE";
"B \NAC \NWC"7;
"S \NAC"
BN"1"62;
%"TAP"
"1","(-3050,2425)","0","mstr_standard","I234";
;
CDS_LIB"mstr_standard"
BODY_TYPE"PLUMBING"
HDL_TAP"TRUE";
"B \NAC \NWC"7;
"S \NAC"
BN"0"66;
%"TAP"
"1","(-3250,2675)","0","mstr_standard","I235";
;
CDS_LIB"mstr_standard"
BODY_TYPE"PLUMBING"
HDL_TAP"TRUE";
"B \NAC \NWC"8;
"S \NAC"
BN"2"57;
%"TAP"
"1","(-3250,2575)","0","mstr_standard","I236";
;
CDS_LIB"mstr_standard"
BODY_TYPE"PLUMBING"
HDL_TAP"TRUE";
"B \NAC \NWC"8;
"S \NAC"
BN"1"61;
%"TAP"
"1","(-3250,2475)","0","mstr_standard","I237";
;
CDS_LIB"mstr_standard"
BODY_TYPE"PLUMBING"
HDL_TAP"TRUE";
"B \NAC \NWC"8;
"S \NAC"
BN"0"65;
%"SCONN288_DDR506112002KQ"
"2","(-4250,3425)","0","pure_quanta","I238";
;
LOCATION"J102"
$SEC"2"
CDS_SEC"2"
VALUE"SCONN288_DDR506112002KQ"
MATERIAL"IO"
PART_TYPE"SMLF"
PART_NUMBER"DFHST8FS479"
CDS_LMAN_SYM_OUTLINE"-600,1150,600,-1150"
NEEDS_NO_SIZE"TRUE"
CDS_LIB"pure_quanta";
"DQS7_A_C||TDQS7_A_C \B"
$PN"178"73;
"DQS6_A_T||TDQS6_A_T"
$PN"168"72;
"DQS8_B_T||TDQS8_B_T"
$PN"283"71;
"DQS8_B_C||TDQS8_B_C \B"
$PN"282"70;
"DQS7_B_T||TDQS7_B_T"
$PN"272"69;
"DQS0_A_C \B"
$PN"12"68;
"DQS0_A_T"
$PN"11"67;
"DQS0_B_C \B"
$PN"105"66;
"DQS0_B_T"
$PN"104"65;
"DQS1_A_C \B"
$PN"23"64;
"DQS1_A_T"
$PN"22"63;
"DQS1_B_C \B"
$PN"116"62;
"DQS1_B_T"
$PN"115"61;
"DQS2_A_C \B"
$PN"34"60;
"DQS2_A_T"
$PN"33"59;
"DQS2_B_C \B"
$PN"127"58;
"DQS2_B_T"
$PN"126"57;
"DQS3_A_C \B"
$PN"45"56;
"DQS3_A_T"
$PN"44"55;
"DQS3_B_C \B"
$PN"138"54;
"DQS3_B_T"
$PN"137"53;
"DQS4_A_C \B"
$PN"56"52;
"DQS4_A_T"
$PN"55"51;
"DQS4_B_C \B"
$PN"238"50;
"DQS4_B_T"
$PN"239"49;
"DQS5_A_C||TDQS5_A_C||DQS5_A_T||TDQS5_A_T \B"
$PN"156"48;
"DQS5_A_T||TDQS5_A_T"
$PN"157"47;
"DQS5_B_C||TDQS5_B_C \B"
$PN"249"46;
"DQS5_B_T||TDQS5_B_T"
$PN"250"45;
"DQS6_A_C||TDQS6_A_C||DQS6_A_T||TDQS6_A_T \B"
$PN"167"44;
"DQS6_B_C||TDQS6_B_C \B"
$PN"260"43;
"DQS6_B_T||TDQS6_B_T"
$PN"261"42;
"DQS7_A_T||TDQS7_A_T"
$PN"179"41;
"DQS7_B_C||TDQS7_B_C \B"
$PN"271"40;
"DQS8_A_C||TDQS8_A_C \B"
$PN"189"39;
"DQS8_A_T||TDQS8_A_T"
$PN"190"38;
"DQS9_A_C||TDQS9_A_C \B"
$PN"200"37;
"DQS9_A_T||TDQS9_A_T"
$PN"201"36;
"DQS9_B_C||TDQS9_B_C \B"
$PN"94"35;
"DQS9_B_T||TDQS9_B_T||DBI4_B_N"
$PN"93"34;
%"GND"
"1","(-2825,5525)","0","pure_quanta_power","I239";
;
CDS_LIB"pure_quanta_power"
BOM_COST"MEM"
SIZE"1B"
ROOM"MEM_EFGH_DECOUPLING_CAPS"
HDL_POWER"GND";
"A<SIZE-1..0>\NAC"177;
%"TAP"
"1","(-7475,3150)","2","mstr_standard","I24";
;
CDS_LIB"mstr_standard"
BODY_TYPE"PLUMBING"
HDL_TAP"TRUE";
"B \NAC \NWC"3;
"S \NAC"
BN"0"150;
%"Q_CAP"
"1","(-2825,5875)","2","pure_quanta","I240";
;
LOCATION"C530"
$SEC"1"
CDS_SEC"1"
MATERIAL"X6S"
TOLERANCE"10%"
VOLTAGE"25V"
PACK_TYPE"C0805"
PART_NUMBER"CH6104KEA00"
VALUE"10UF"
BOM_COST"MEM"
CDS_LIB"pure_quanta"
ROOM"MEM_CH_A_CPU0_DIMM1";
"B"
$PN"2"177;
"A"
$PN"1"31;
%"Q_CAP"
"1","(-2250,5875)","2","pure_quanta","I241";
;
LOCATION"C531"
$SEC"1"
CDS_SEC"1"
TOLERANCE"10%"
VALUE"10UF"
VOLTAGE"25V"
PACK_TYPE"C0805"
PART_NUMBER"CH6104KEA00"
MATERIAL"X6S"
BOM_COST"MEM"
CDS_LIB"pure_quanta"
ROOM"MEM_CH_A_CPU0_DIMM1";
"B"
$PN"2"177;
"A"
$PN"1"31;
%"UNIVERSAL_POWER"
"1","(-2825,6200)","0","pure_quanta_power","I242";
;
HDL_POWER"P12V_MEM_1"
CDS_LIB"pure_quanta_power";
"A"31;
%"Q_RES"
"1","(-7525,2625)","0","pure_quanta","I244";
;
$LOCATION"R1586"
CDS_LOCATION"R1586"
$SEC"1"
CDS_SEC"1"
VALUE"49.9"
CDS_LIB"pure_quanta"
PART_NUMBER"CS04992FB07"
TOLERANCE"1%"
WATTAGE"1/16W"
PACK_TYPE"0402LF"
MATERIAL"CHIP";
"B"
$PN"2"16;
"A"
$PN"1"15;
%"TAP"
"1","(-7475,3350)","2","mstr_standard","I25";
;
CDS_LIB"mstr_standard"
BODY_TYPE"PLUMBING"
HDL_TAP"TRUE";
"B \NAC \NWC"3;
"S \NAC"
BN"4"154;
%"TAP"
"1","(-7475,3300)","2","mstr_standard","I26";
;
CDS_LIB"mstr_standard"
BODY_TYPE"PLUMBING"
HDL_TAP"TRUE";
"B \NAC \NWC"3;
"S \NAC"
BN"3"153;
%"TAP"
"1","(-7475,3250)","2","mstr_standard","I27";
;
CDS_LIB"mstr_standard"
BODY_TYPE"PLUMBING"
HDL_TAP"TRUE";
"B \NAC \NWC"3;
"S \NAC"
BN"2"152;
%"TAP"
"1","(-7475,3400)","2","mstr_standard","I28";
;
CDS_LIB"mstr_standard"
BODY_TYPE"PLUMBING"
HDL_TAP"TRUE";
"B \NAC \NWC"3;
"S \NAC"
BN"5"155;
%"TAP"
"1","(-7475,3450)","2","mstr_standard","I29";
;
CDS_LIB"mstr_standard"
BODY_TYPE"PLUMBING"
HDL_TAP"TRUE";
"B \NAC \NWC"3;
"S \NAC"
BN"6"156;
%"TAP"
"1","(-7475,3650)","2","mstr_standard","I30";
;
CDS_LIB"mstr_standard"
BODY_TYPE"PLUMBING"
HDL_TAP"TRUE";
"B \NAC \NWC"1;
"S \NAC"
BN"1"173;
%"TAP"
"1","(-7475,3700)","2","mstr_standard","I31";
;
CDS_LIB"mstr_standard"
BODY_TYPE"PLUMBING"
HDL_TAP"TRUE";
"B \NAC \NWC"1;
"S \NAC"
BN"2"158;
%"TAP"
"1","(-7475,3500)","2","mstr_standard","I32";
;
CDS_LIB"mstr_standard"
BODY_TYPE"PLUMBING"
HDL_TAP"TRUE";
"B \NAC \NWC"3;
"S \NAC"
BN"7"172;
%"TAP"
"1","(-7475,3600)","2","mstr_standard","I33";
;
CDS_LIB"mstr_standard"
BODY_TYPE"PLUMBING"
HDL_TAP"TRUE";
"B \NAC \NWC"1;
"S \NAC"
BN"0"157;
%"TAP"
"1","(-7475,3750)","2","mstr_standard","I34";
;
CDS_LIB"mstr_standard"
BODY_TYPE"PLUMBING"
HDL_TAP"TRUE";
"B \NAC \NWC"1;
"S \NAC"
BN"3"159;
%"TAP"
"1","(-5775,2200)","0","mstr_standard","I42";
;
CDS_LIB"mstr_standard"
BODY_TYPE"PLUMBING"
HDL_TAP"TRUE";
"B \NAC \NWC"5;
"S \NAC"
BN"1"82;
%"TAP"
"1","(-5775,2150)","0","mstr_standard","I43";
;
CDS_LIB"mstr_standard"
BODY_TYPE"PLUMBING"
HDL_TAP"TRUE";
"B \NAC \NWC"5;
"S \NAC"
BN"0"81;
%"TAP"
"1","(-5775,2400)","0","mstr_standard","I44";
;
CDS_LIB"mstr_standard"
BODY_TYPE"PLUMBING"
HDL_TAP"TRUE";
"B \NAC \NWC"5;
"S \NAC"
BN"5"86;
%"TAP"
"1","(-5775,2450)","0","mstr_standard","I45";
;
CDS_LIB"mstr_standard"
BODY_TYPE"PLUMBING"
HDL_TAP"TRUE";
"B \NAC \NWC"5;
"S \NAC"
BN"6"87;
%"TAP"
"1","(-5775,2250)","0","mstr_standard","I46";
;
CDS_LIB"mstr_standard"
BODY_TYPE"PLUMBING"
HDL_TAP"TRUE";
"B \NAC \NWC"5;
"S \NAC"
BN"2"83;
%"TAP"
"1","(-5775,2300)","0","mstr_standard","I47";
;
CDS_LIB"mstr_standard"
BODY_TYPE"PLUMBING"
HDL_TAP"TRUE";
"B \NAC \NWC"5;
"S \NAC"
BN"3"84;
%"TAP"
"1","(-5775,2350)","0","mstr_standard","I48";
;
CDS_LIB"mstr_standard"
BODY_TYPE"PLUMBING"
HDL_TAP"TRUE";
"B \NAC \NWC"5;
"S \NAC"
BN"4"85;
%"TAP"
"1","(-5775,2650)","0","mstr_standard","I49";
;
CDS_LIB"mstr_standard"
BODY_TYPE"PLUMBING"
HDL_TAP"TRUE";
"B \NAC \NWC"5;
"S \NAC"
BN"10"91;
%"VCC_CORE"
"1","(-8575,3425)","0","mstr_symbols","I5";
;
HDL_POWER"P3V3_STBY"
CDS_LIB"mstr_symbols"
VOLTAGE"3.3"
ROOM"PVCCINFAON_CPU1_CTRL";
"A"19;
%"TAP"
"1","(-5775,2700)","0","mstr_standard","I50";
;
CDS_LIB"mstr_standard"
BODY_TYPE"PLUMBING"
HDL_TAP"TRUE";
"B \NAC \NWC"5;
"S \NAC"
BN"11"92;
%"TAP"
"1","(-5775,2500)","0","mstr_standard","I51";
;
CDS_LIB"mstr_standard"
BODY_TYPE"PLUMBING"
HDL_TAP"TRUE";
"B \NAC \NWC"5;
"S \NAC"
BN"7"88;
%"TAP"
"1","(-5775,2550)","0","mstr_standard","I52";
;
CDS_LIB"mstr_standard"
BODY_TYPE"PLUMBING"
HDL_TAP"TRUE";
"B \NAC \NWC"5;
"S \NAC"
BN"8"89;
%"TAP"
"1","(-5775,2600)","0","mstr_standard","I53";
;
CDS_LIB"mstr_standard"
BODY_TYPE"PLUMBING"
HDL_TAP"TRUE";
"B \NAC \NWC"5;
"S \NAC"
BN"9"90;
%"TAP"
"1","(-5775,2950)","0","mstr_standard","I54";
;
CDS_LIB"mstr_standard"
BODY_TYPE"PLUMBING"
HDL_TAP"TRUE";
"B \NAC \NWC"5;
"S \NAC"
BN"16"97;
%"TAP"
"1","(-5775,2900)","0","mstr_standard","I55";
;
CDS_LIB"mstr_standard"
BODY_TYPE"PLUMBING"
HDL_TAP"TRUE";
"B \NAC \NWC"5;
"S \NAC"
BN"15"96;
%"TAP"
"1","(-5775,3000)","0","mstr_standard","I56";
;
CDS_LIB"mstr_standard"
BODY_TYPE"PLUMBING"
HDL_TAP"TRUE";
"B \NAC \NWC"5;
"S \NAC"
BN"17"98;
%"TAP"
"1","(-5775,2750)","0","mstr_standard","I57";
;
CDS_LIB"mstr_standard"
BODY_TYPE"PLUMBING"
HDL_TAP"TRUE";
"B \NAC \NWC"5;
"S \NAC"
BN"12"93;
%"TAP"
"1","(-5775,2800)","0","mstr_standard","I58";
;
CDS_LIB"mstr_standard"
BODY_TYPE"PLUMBING"
HDL_TAP"TRUE";
"B \NAC \NWC"5;
"S \NAC"
BN"13"94;
%"TAP"
"1","(-5775,2850)","0","mstr_standard","I59";
;
CDS_LIB"mstr_standard"
BODY_TYPE"PLUMBING"
HDL_TAP"TRUE";
"B \NAC \NWC"5;
"S \NAC"
BN"14"95;
%"TAP"
"1","(-5775,3150)","0","mstr_standard","I60";
;
CDS_LIB"mstr_standard"
BODY_TYPE"PLUMBING"
HDL_TAP"TRUE";
"B \NAC \NWC"5;
"S \NAC"
BN"20"101;
%"TAP"
"1","(-5775,3200)","0","mstr_standard","I61";
;
CDS_LIB"mstr_standard"
BODY_TYPE"PLUMBING"
HDL_TAP"TRUE";
"B \NAC \NWC"5;
"S \NAC"
BN"21"102;
%"TAP"
"1","(-5775,3250)","0","mstr_standard","I62";
;
CDS_LIB"mstr_standard"
BODY_TYPE"PLUMBING"
HDL_TAP"TRUE";
"B \NAC \NWC"5;
"S \NAC"
BN"22"103;
%"TAP"
"1","(-5775,3050)","0","mstr_standard","I63";
;
CDS_LIB"mstr_standard"
BODY_TYPE"PLUMBING"
HDL_TAP"TRUE";
"B \NAC \NWC"5;
"S \NAC"
BN"18"99;
%"TAP"
"1","(-5775,3100)","0","mstr_standard","I64";
;
CDS_LIB"mstr_standard"
BODY_TYPE"PLUMBING"
HDL_TAP"TRUE";
"B \NAC \NWC"5;
"S \NAC"
BN"19"100;
%"TAP"
"1","(-5775,3400)","0","mstr_standard","I65";
;
CDS_LIB"mstr_standard"
BODY_TYPE"PLUMBING"
HDL_TAP"TRUE";
"B \NAC \NWC"5;
"S \NAC"
BN"25"106;
%"TAP"
"1","(-5775,3450)","0","mstr_standard","I66";
;
CDS_LIB"mstr_standard"
BODY_TYPE"PLUMBING"
HDL_TAP"TRUE";
"B \NAC \NWC"5;
"S \NAC"
BN"26"107;
%"TAP"
"1","(-5775,3500)","0","mstr_standard","I67";
;
CDS_LIB"mstr_standard"
BODY_TYPE"PLUMBING"
HDL_TAP"TRUE";
"B \NAC \NWC"5;
"S \NAC"
BN"27"108;
%"TAP"
"1","(-5775,3300)","0","mstr_standard","I68";
;
CDS_LIB"mstr_standard"
BODY_TYPE"PLUMBING"
HDL_TAP"TRUE";
"B \NAC \NWC"5;
"S \NAC"
BN"23"104;
%"TAP"
"1","(-5775,3350)","0","mstr_standard","I69";
;
CDS_LIB"mstr_standard"
BODY_TYPE"PLUMBING"
HDL_TAP"TRUE";
"B \NAC \NWC"5;
"S \NAC"
BN"24"105;
%"TAP"
"1","(-5775,3650)","0","mstr_standard","I70";
;
CDS_LIB"mstr_standard"
BODY_TYPE"PLUMBING"
HDL_TAP"TRUE";
"B \NAC \NWC"5;
"S \NAC"
BN"30"111;
%"TAP"
"1","(-5775,3700)","0","mstr_standard","I71";
;
CDS_LIB"mstr_standard"
BODY_TYPE"PLUMBING"
HDL_TAP"TRUE";
"B \NAC \NWC"5;
"S \NAC"
BN"31"112;
%"TAP"
"1","(-5775,3550)","0","mstr_standard","I72";
;
CDS_LIB"mstr_standard"
BODY_TYPE"PLUMBING"
HDL_TAP"TRUE";
"B \NAC \NWC"5;
"S \NAC"
BN"28"109;
%"TAP"
"1","(-5775,3600)","0","mstr_standard","I73";
;
CDS_LIB"mstr_standard"
BODY_TYPE"PLUMBING"
HDL_TAP"TRUE";
"B \NAC \NWC"5;
"S \NAC"
BN"29"110;
%"TAP"
"1","(-7475,3800)","2","mstr_standard","I76";
;
CDS_LIB"mstr_standard"
BODY_TYPE"PLUMBING"
HDL_TAP"TRUE";
"B \NAC \NWC"1;
"S \NAC"
BN"4"174;
%"TAP"
"1","(-7475,3850)","2","mstr_standard","I77";
;
CDS_LIB"mstr_standard"
BODY_TYPE"PLUMBING"
HDL_TAP"TRUE";
"B \NAC \NWC"1;
"S \NAC"
BN"5"160;
%"TAP"
"1","(-7475,3900)","2","mstr_standard","I78";
;
CDS_LIB"mstr_standard"
BODY_TYPE"PLUMBING"
HDL_TAP"TRUE";
"B \NAC \NWC"1;
"S \NAC"
BN"6"161;
%"TAP"
"1","(-7475,3950)","2","mstr_standard","I79";
;
CDS_LIB"mstr_standard"
BODY_TYPE"PLUMBING"
HDL_TAP"TRUE";
"B \NAC \NWC"1;
"S \NAC"
BN"7"175;
%"TAP"
"1","(-7475,4750)","2","mstr_standard","I80";
;
CDS_LIB"mstr_standard"
BODY_TYPE"PLUMBING"
HDL_TAP"TRUE";
"B \NAC \NWC"2;
"S \NAC"
BN"2"169;
%"TAP"
"1","(-7475,4700)","2","mstr_standard","I81";
;
CDS_LIB"mstr_standard"
BODY_TYPE"PLUMBING"
HDL_TAP"TRUE";
"B \NAC \NWC"2;
"S \NAC"
BN"1"170;
%"TAP"
"1","(-7475,4650)","2","mstr_standard","I82";
;
CDS_LIB"mstr_standard"
BODY_TYPE"PLUMBING"
HDL_TAP"TRUE";
"B \NAC \NWC"2;
"S \NAC"
BN"0"171;
%"TAP"
"1","(-7475,4850)","2","mstr_standard","I83";
;
CDS_LIB"mstr_standard"
BODY_TYPE"PLUMBING"
HDL_TAP"TRUE";
"B \NAC \NWC"2;
"S \NAC"
BN"4"166;
%"TAP"
"1","(-7475,4800)","2","mstr_standard","I84";
;
CDS_LIB"mstr_standard"
BODY_TYPE"PLUMBING"
HDL_TAP"TRUE";
"B \NAC \NWC"2;
"S \NAC"
BN"3"168;
%"TAP"
"1","(-7475,4950)","2","mstr_standard","I85";
;
CDS_LIB"mstr_standard"
BODY_TYPE"PLUMBING"
HDL_TAP"TRUE";
"B \NAC \NWC"2;
"S \NAC"
BN"6"162;
%"TAP"
"1","(-7475,4900)","2","mstr_standard","I86";
;
CDS_LIB"mstr_standard"
BODY_TYPE"PLUMBING"
HDL_TAP"TRUE";
"B \NAC \NWC"2;
"S \NAC"
BN"5"164;
%"TAP"
"1","(-7475,5050)","2","mstr_standard","I87";
;
CDS_LIB"mstr_standard"
BODY_TYPE"PLUMBING"
HDL_TAP"TRUE";
"B \NAC \NWC"9;
"S \NAC"
BN"0"30;
%"TAP"
"1","(-7475,5150)","2","mstr_standard","I88";
;
CDS_LIB"mstr_standard"
BODY_TYPE"PLUMBING"
HDL_TAP"TRUE";
"B \NAC \NWC"9;
"S \NAC"
BN"2"28;
%"TAP"
"1","(-7475,5100)","2","mstr_standard","I89";
;
CDS_LIB"mstr_standard"
BODY_TYPE"PLUMBING"
HDL_TAP"TRUE";
"B \NAC \NWC"9;
"S \NAC"
BN"1"29;
%"TAP"
"1","(-7475,5200)","2","mstr_standard","I90";
;
CDS_LIB"mstr_standard"
BODY_TYPE"PLUMBING"
HDL_TAP"TRUE";
"B \NAC \NWC"9;
"S \NAC"
BN"3"27;
%"TAP"
"1","(-7475,5250)","2","mstr_standard","I91";
;
CDS_LIB"mstr_standard"
BODY_TYPE"PLUMBING"
HDL_TAP"TRUE";
"B \NAC \NWC"9;
"S \NAC"
BN"4"167;
%"TAP"
"1","(-7475,5300)","2","mstr_standard","I92";
;
CDS_LIB"mstr_standard"
BODY_TYPE"PLUMBING"
HDL_TAP"TRUE";
"B \NAC \NWC"9;
"S \NAC"
BN"5"165;
%"TAP"
"1","(-7475,5350)","2","mstr_standard","I93";
;
CDS_LIB"mstr_standard"
BODY_TYPE"PLUMBING"
HDL_TAP"TRUE";
"B \NAC \NWC"9;
"S \NAC"
BN"6"163;
%"TAP"
"1","(-5775,4000)","0","mstr_standard","I94";
;
CDS_LIB"mstr_standard"
BODY_TYPE"PLUMBING"
HDL_TAP"TRUE";
"B \NAC \NWC"4;
"S \NAC"
BN"4"117;
%"TAP"
"1","(-5775,3900)","0","mstr_standard","I95";
;
CDS_LIB"mstr_standard"
BODY_TYPE"PLUMBING"
HDL_TAP"TRUE";
"B \NAC \NWC"4;
"S \NAC"
BN"2"115;
%"TAP"
"1","(-5775,3950)","0","mstr_standard","I96";
;
CDS_LIB"mstr_standard"
BODY_TYPE"PLUMBING"
HDL_TAP"TRUE";
"B \NAC \NWC"4;
"S \NAC"
BN"3"116;
%"TAP"
"1","(-5775,3800)","0","mstr_standard","I97";
;
CDS_LIB"mstr_standard"
BODY_TYPE"PLUMBING"
HDL_TAP"TRUE";
"B \NAC \NWC"4;
"S \NAC"
BN"0"113;
%"TAP"
"1","(-5775,3850)","0","mstr_standard","I98";
;
CDS_LIB"mstr_standard"
BODY_TYPE"PLUMBING"
HDL_TAP"TRUE";
"B \NAC \NWC"4;
"S \NAC"
BN"1"114;
%"TAP"
"1","(-5775,4150)","0","mstr_standard","I99";
;
CDS_LIB"mstr_standard"
BODY_TYPE"PLUMBING"
HDL_TAP"TRUE";
"B \NAC \NWC"4;
"S \NAC"
BN"7"120;
END.
